(kicad_pcb
	(version 20260206)
	(generator "pcbnew")
	(generator_version "10.0")
	(general
		(thickness 1.6)
		(legacy_teardrops no)
	)
	(paper "A4")
	(title_block
		(title "12092022_DA0F0TMDCD0_F0T_Management_Board_D_brd_V3_OCP.brd")
		(comment 1 "Grand Teton / footprints 1099-1104 of 1440")
	)
	(layers
		(0 "F.Cu" signal "TOP")
		(4 "In1.Cu" signal "GND")
		(6 "In2.Cu" signal "IN1")
		(8 "In3.Cu" signal "GND1")
		(10 "In4.Cu" signal "IN2")
		(12 "In5.Cu" signal "VCC")
		(14 "In6.Cu" signal "VCC1")
		(16 "In7.Cu" signal "IN3")
		(18 "In8.Cu" signal "GND2")
		(20 "In9.Cu" signal "IN4")
		(22 "In10.Cu" signal "GND3")
		(2 "B.Cu" signal "BOTTOM")
		(9 "F.Adhes" user "F.Adhesive")
		(11 "B.Adhes" user "B.Adhesive")
		(13 "F.Paste" user "Package Geometry/Pastemask Top")
		(15 "B.Paste" user "Package Geometry/Pastemask Bottom")
		(5 "F.SilkS" user "Ref Des/Silkscreen Top")
		(7 "B.SilkS" user "Ref Des/Silkscreen Bottom")
		(1 "F.Mask" user "Board Geometry/Soldermask Top")
		(3 "B.Mask" user "Board Geometry/Soldermask Bottom")
		(17 "Dwgs.User" user "User.Drawings")
		(19 "Cmts.User" user "User.Comments")
		(21 "Eco1.User" user "User.Eco1")
		(23 "Eco2.User" user "User.Eco2")
		(25 "Edge.Cuts" user "Board Geometry/Outline")
		(27 "Margin" user)
		(31 "F.CrtYd" user "Package Geometry/Place Bound Top")
		(29 "B.CrtYd" user "Package Geometry/Place Bound Bottom")
		(35 "F.Fab" user "Ref Des/Assembly Top")
		(33 "B.Fab" user "Ref Des/Assembly Bottom")
	)
	(footprint ""
		(layer "B.Cu")
		(at 77.707744 -35.540188 -90)
		(property "Reference" "R332"
			(at 0 0 90)
			(layer "B.SilkS")
			(hide yes)
			(effects
				(font
					(size 1.27 1.27)
				)
				(justify mirror)
			)
		)
		(property "Value" ""
			(at 0 0 90)
			(layer "B.Fab")
			(effects
				(font
					(size 1.27 1.27)
				)
				(justify mirror)
			)
		)
		(duplicate_pad_numbers_are_jumpers no)
		(fp_line
			(start -0.7874 0.4064)
			(end 0.7874 0.4064)
			(stroke
				(width 0.1524)
				(type default)
			)
			(layer "B.SilkS")
		)
		(fp_line
			(start 0.7874 0.4064)
			(end 0.7874 -0.4064)
			(stroke
				(width 0.1524)
				(type default)
			)
			(layer "B.SilkS")
		)
		(fp_line
			(start -0.7874 -0.4064)
			(end -0.7874 0.4064)
			(stroke
				(width 0.1524)
				(type default)
			)
			(layer "B.SilkS")
		)
		(fp_line
			(start 0.7874 -0.4064)
			(end -0.7874 -0.4064)
			(stroke
				(width 0.1524)
				(type default)
			)
			(layer "B.SilkS")
		)
		(fp_line
			(start -0.67945 0.3048)
			(end -0.120396 0.3048)
			(stroke
				(width 0.1)
				(type default)
			)
			(layer "B.Fab")
		)
		(fp_line
			(start -0.120396 0.3048)
			(end -0.120396 0.2794)
			(stroke
				(width 0.1)
				(type default)
			)
			(layer "B.Fab")
		)
		(fp_line
			(start 0.12065 0.3048)
			(end 0.67945 0.3048)
			(stroke
				(width 0.1)
				(type default)
			)
			(layer "B.Fab")
		)
		(fp_line
			(start 0.67945 0.3048)
			(end 0.67945 -0.305054)
			(stroke
				(width 0.1)
				(type default)
			)
			(layer "B.Fab")
		)
		(fp_line
			(start -0.120396 0.2794)
			(end 0.12065 0.2794)
			(stroke
				(width 0.1)
				(type default)
			)
			(layer "B.Fab")
		)
		(fp_line
			(start 0.12065 0.2794)
			(end 0.12065 0.3048)
			(stroke
				(width 0.1)
				(type default)
			)
			(layer "B.Fab")
		)
		(fp_line
			(start -0.12065 -0.2794)
			(end -0.12065 -0.3048)
			(stroke
				(width 0.1)
				(type default)
			)
			(layer "B.Fab")
		)
		(fp_line
			(start 0.12065 -0.2794)
			(end -0.12065 -0.2794)
			(stroke
				(width 0.1)
				(type default)
			)
			(layer "B.Fab")
		)
		(fp_line
			(start -0.67945 -0.3048)
			(end -0.67945 0.3048)
			(stroke
				(width 0.1)
				(type default)
			)
			(layer "B.Fab")
		)
		(fp_line
			(start -0.12065 -0.3048)
			(end -0.67945 -0.3048)
			(stroke
				(width 0.1)
				(type default)
			)
			(layer "B.Fab")
		)
		(fp_line
			(start 0.12065 -0.305054)
			(end 0.12065 -0.2794)
			(stroke
				(width 0.1)
				(type default)
			)
			(layer "B.Fab")
		)
		(fp_line
			(start 0.67945 -0.305054)
			(end 0.12065 -0.305054)
			(stroke
				(width 0.1)
				(type default)
			)
			(layer "B.Fab")
		)
		(pad "1" smd circle
			(at 0.40005 0 90)
			(size 0 0)
			(layers "B.Cu" "B.Mask" "B.Paste")
			(net "GND")
		)
		(pad "2" smd circle
			(at -0.40005 0 90)
			(size 0 0)
			(layers "B.Cu" "B.Mask" "B.Paste")
			(net "M_BMC_DDR4_MA<6>")
		)
	)
	(footprint ""
		(layer "B.Cu")
		(at 36.77412 -96.20504 180)
		(property "Reference" "R732"
			(at 0 0 0)
			(layer "B.SilkS")
			(hide yes)
			(effects
				(font
					(size 1.27 1.27)
				)
				(justify mirror)
			)
		)
		(property "Value" ""
			(at 0 0 0)
			(layer "B.Fab")
			(effects
				(font
					(size 1.27 1.27)
				)
				(justify mirror)
			)
		)
		(duplicate_pad_numbers_are_jumpers no)
		(fp_line
			(start 0.7874 0.4064)
			(end 0.7874 -0.4064)
			(stroke
				(width 0.1524)
				(type default)
			)
			(layer "B.SilkS")
		)
		(fp_line
			(start 0.7874 -0.4064)
			(end -0.7874 -0.4064)
			(stroke
				(width 0.1524)
				(type default)
			)
			(layer "B.SilkS")
		)
		(fp_line
			(start -0.7874 0.4064)
			(end 0.7874 0.4064)
			(stroke
				(width 0.1524)
				(type default)
			)
			(layer "B.SilkS")
		)
		(fp_line
			(start -0.7874 -0.4064)
			(end -0.7874 0.4064)
			(stroke
				(width 0.1524)
				(type default)
			)
			(layer "B.SilkS")
		)
		(fp_line
			(start 0.67945 0.3048)
			(end 0.67945 -0.305054)
			(stroke
				(width 0.1)
				(type default)
			)
			(layer "B.Fab")
		)
		(fp_line
			(start 0.67945 -0.305054)
			(end 0.12065 -0.305054)
			(stroke
				(width 0.1)
				(type default)
			)
			(layer "B.Fab")
		)
		(fp_line
			(start 0.12065 0.3048)
			(end 0.67945 0.3048)
			(stroke
				(width 0.1)
				(type default)
			)
			(layer "B.Fab")
		)
		(fp_line
			(start 0.12065 0.2794)
			(end 0.12065 0.3048)
			(stroke
				(width 0.1)
				(type default)
			)
			(layer "B.Fab")
		)
		(fp_line
			(start 0.12065 -0.2794)
			(end -0.12065 -0.2794)
			(stroke
				(width 0.1)
				(type default)
			)
			(layer "B.Fab")
		)
		(fp_line
			(start 0.12065 -0.305054)
			(end 0.12065 -0.2794)
			(stroke
				(width 0.1)
				(type default)
			)
			(layer "B.Fab")
		)
		(fp_line
			(start -0.120396 0.3048)
			(end -0.120396 0.2794)
			(stroke
				(width 0.1)
				(type default)
			)
			(layer "B.Fab")
		)
		(fp_line
			(start -0.120396 0.2794)
			(end 0.12065 0.2794)
			(stroke
				(width 0.1)
				(type default)
			)
			(layer "B.Fab")
		)
		(fp_line
			(start -0.12065 -0.2794)
			(end -0.12065 -0.3048)
			(stroke
				(width 0.1)
				(type default)
			)
			(layer "B.Fab")
		)
		(fp_line
			(start -0.12065 -0.3048)
			(end -0.67945 -0.3048)
			(stroke
				(width 0.1)
				(type default)
			)
			(layer "B.Fab")
		)
		(fp_line
			(start -0.67945 0.3048)
			(end -0.120396 0.3048)
			(stroke
				(width 0.1)
				(type default)
			)
			(layer "B.Fab")
		)
		(fp_line
			(start -0.67945 -0.3048)
			(end -0.67945 0.3048)
			(stroke
				(width 0.1)
				(type default)
			)
			(layer "B.Fab")
		)
		(pad "1" smd circle
			(at 0.40005 0)
			(size 0 0)
			(layers "B.Cu" "B.Mask" "B.Paste")
			(net "SMB_DEBUG_AUX_LVC3_USB_SCL")
		)
		(pad "2" smd circle
			(at -0.40005 0)
			(size 0 0)
			(layers "B.Cu" "B.Mask" "B.Paste")
			(net "SMB_DEBUG_AUX_LVC3_USB_R2_SCL")
		)
	)
	(footprint ""
		(layer "B.Cu")
		(at 76.582778 -48.63084 -90)
		(property "Reference" "C12"
			(at 0 0 90)
			(layer "B.SilkS")
			(hide yes)
			(effects
				(font
					(size 1.27 1.27)
				)
				(justify mirror)
			)
		)
		(property "Value" ""
			(at 0 0 90)
			(layer "B.Fab")
			(effects
				(font
					(size 1.27 1.27)
				)
				(justify mirror)
			)
		)
		(duplicate_pad_numbers_are_jumpers no)
		(fp_line
			(start -0.7874 0.4064)
			(end 0.7874 0.4064)
			(stroke
				(width 0.1524)
				(type default)
			)
			(layer "B.SilkS")
		)
		(fp_line
			(start 0.7874 0.4064)
			(end 0.7874 -0.4064)
			(stroke
				(width 0.1524)
				(type default)
			)
			(layer "B.SilkS")
		)
		(fp_line
			(start -0.7874 -0.4064)
			(end -0.7874 0.4064)
			(stroke
				(width 0.1524)
				(type default)
			)
			(layer "B.SilkS")
		)
		(fp_line
			(start 0.7874 -0.4064)
			(end -0.7874 -0.4064)
			(stroke
				(width 0.1524)
				(type default)
			)
			(layer "B.SilkS")
		)
		(fp_line
			(start -0.67945 0.3048)
			(end -0.120396 0.3048)
			(stroke
				(width 0.1)
				(type default)
			)
			(layer "B.Fab")
		)
		(fp_line
			(start -0.120396 0.3048)
			(end -0.120396 0.2794)
			(stroke
				(width 0.1)
				(type default)
			)
			(layer "B.Fab")
		)
		(fp_line
			(start 0.12065 0.3048)
			(end 0.67945 0.3048)
			(stroke
				(width 0.1)
				(type default)
			)
			(layer "B.Fab")
		)
		(fp_line
			(start 0.67945 0.3048)
			(end 0.67945 -0.305054)
			(stroke
				(width 0.1)
				(type default)
			)
			(layer "B.Fab")
		)
		(fp_line
			(start -0.120396 0.2794)
			(end 0.12065 0.2794)
			(stroke
				(width 0.1)
				(type default)
			)
			(layer "B.Fab")
		)
		(fp_line
			(start 0.12065 0.2794)
			(end 0.12065 0.3048)
			(stroke
				(width 0.1)
				(type default)
			)
			(layer "B.Fab")
		)
		(fp_line
			(start -0.12065 -0.2794)
			(end -0.12065 -0.3048)
			(stroke
				(width 0.1)
				(type default)
			)
			(layer "B.Fab")
		)
		(fp_line
			(start 0.12065 -0.2794)
			(end -0.12065 -0.2794)
			(stroke
				(width 0.1)
				(type default)
			)
			(layer "B.Fab")
		)
		(fp_line
			(start -0.67945 -0.3048)
			(end -0.67945 0.3048)
			(stroke
				(width 0.1)
				(type default)
			)
			(layer "B.Fab")
		)
		(fp_line
			(start -0.12065 -0.3048)
			(end -0.67945 -0.3048)
			(stroke
				(width 0.1)
				(type default)
			)
			(layer "B.Fab")
		)
		(fp_line
			(start 0.12065 -0.305054)
			(end 0.12065 -0.2794)
			(stroke
				(width 0.1)
				(type default)
			)
			(layer "B.Fab")
		)
		(fp_line
			(start 0.67945 -0.305054)
			(end 0.12065 -0.305054)
			(stroke
				(width 0.1)
				(type default)
			)
			(layer "B.Fab")
		)
		(pad "1" smd circle
			(at 0.40005 0 90)
			(size 0 0)
			(layers "B.Cu" "B.Mask" "B.Paste")
			(net "M_BMC_DDR4_MCLK_C")
		)
		(pad "2" smd circle
			(at -0.40005 0 90)
			(size 0 0)
			(layers "B.Cu" "B.Mask" "B.Paste")
			(net "GND")
		)
	)
	(footprint ""
		(layer "B.Cu")
		(at 77.47 -33.34766)
		(property "Reference" "R695"
			(at 0 0 0)
			(layer "B.SilkS")
			(hide yes)
			(effects
				(font
					(size 1.27 1.27)
				)
				(justify mirror)
			)
		)
		(property "Value" ""
			(at 0 0 0)
			(layer "B.Fab")
			(effects
				(font
					(size 1.27 1.27)
				)
				(justify mirror)
			)
		)
		(duplicate_pad_numbers_are_jumpers no)
		(fp_line
			(start -0.7874 -0.4064)
			(end -0.7874 0.4064)
			(stroke
				(width 0.1524)
				(type default)
			)
			(layer "B.SilkS")
		)
		(fp_line
			(start -0.7874 0.4064)
			(end 0.7874 0.4064)
			(stroke
				(width 0.1524)
				(type default)
			)
			(layer "B.SilkS")
		)
		(fp_line
			(start 0.7874 -0.4064)
			(end -0.7874 -0.4064)
			(stroke
				(width 0.1524)
				(type default)
			)
			(layer "B.SilkS")
		)
		(fp_line
			(start 0.7874 0.4064)
			(end 0.7874 -0.4064)
			(stroke
				(width 0.1524)
				(type default)
			)
			(layer "B.SilkS")
		)
		(fp_line
			(start -0.67945 -0.3048)
			(end -0.67945 0.3048)
			(stroke
				(width 0.1)
				(type default)
			)
			(layer "B.Fab")
		)
		(fp_line
			(start -0.67945 0.3048)
			(end -0.120396 0.3048)
			(stroke
				(width 0.1)
				(type default)
			)
			(layer "B.Fab")
		)
		(fp_line
			(start -0.12065 -0.3048)
			(end -0.67945 -0.3048)
			(stroke
				(width 0.1)
				(type default)
			)
			(layer "B.Fab")
		)
		(fp_line
			(start -0.12065 -0.2794)
			(end -0.12065 -0.3048)
			(stroke
				(width 0.1)
				(type default)
			)
			(layer "B.Fab")
		)
		(fp_line
			(start -0.120396 0.2794)
			(end 0.12065 0.2794)
			(stroke
				(width 0.1)
				(type default)
			)
			(layer "B.Fab")
		)
		(fp_line
			(start -0.120396 0.3048)
			(end -0.120396 0.2794)
			(stroke
				(width 0.1)
				(type default)
			)
			(layer "B.Fab")
		)
		(fp_line
			(start 0.12065 -0.305054)
			(end 0.12065 -0.2794)
			(stroke
				(width 0.1)
				(type default)
			)
			(layer "B.Fab")
		)
		(fp_line
			(start 0.12065 -0.2794)
			(end -0.12065 -0.2794)
			(stroke
				(width 0.1)
				(type default)
			)
			(layer "B.Fab")
		)
		(fp_line
			(start 0.12065 0.2794)
			(end 0.12065 0.3048)
			(stroke
				(width 0.1)
				(type default)
			)
			(layer "B.Fab")
		)
		(fp_line
			(start 0.12065 0.3048)
			(end 0.67945 0.3048)
			(stroke
				(width 0.1)
				(type default)
			)
			(layer "B.Fab")
		)
		(fp_line
			(start 0.67945 -0.305054)
			(end 0.12065 -0.305054)
			(stroke
				(width 0.1)
				(type default)
			)
			(layer "B.Fab")
		)
		(fp_line
			(start 0.67945 0.3048)
			(end 0.67945 -0.305054)
			(stroke
				(width 0.1)
				(type default)
			)
			(layer "B.Fab")
		)
		(pad "1" smd circle
			(at 0.40005 0 180)
			(size 0 0)
			(layers "B.Cu" "B.Mask" "B.Paste")
			(net "LED_POSTCODE_4")
		)
		(pad "2" smd circle
			(at -0.40005 0 180)
			(size 0 0)
			(layers "B.Cu" "B.Mask" "B.Paste")
			(net "LED_POSTCODE_4_R1")
		)
	)
	(footprint ""
		(layer "B.Cu")
		(at 56.87568 -95.26524 -90)
		(property "Reference" "R738"
			(at 0 0 90)
			(layer "B.SilkS")
			(hide yes)
			(effects
				(font
					(size 1.27 1.27)
				)
				(justify mirror)
			)
		)
		(property "Value" ""
			(at 0 0 90)
			(layer "B.Fab")
			(effects
				(font
					(size 1.27 1.27)
				)
				(justify mirror)
			)
		)
		(duplicate_pad_numbers_are_jumpers no)
		(fp_line
			(start -0.7874 0.4064)
			(end 0.7874 0.4064)
			(stroke
				(width 0.1524)
				(type default)
			)
			(layer "B.SilkS")
		)
		(fp_line
			(start 0.7874 0.4064)
			(end 0.7874 -0.4064)
			(stroke
				(width 0.1524)
				(type default)
			)
			(layer "B.SilkS")
		)
		(fp_line
			(start -0.7874 -0.4064)
			(end -0.7874 0.4064)
			(stroke
				(width 0.1524)
				(type default)
			)
			(layer "B.SilkS")
		)
		(fp_line
			(start 0.7874 -0.4064)
			(end -0.7874 -0.4064)
			(stroke
				(width 0.1524)
				(type default)
			)
			(layer "B.SilkS")
		)
		(fp_line
			(start -0.67945 0.3048)
			(end -0.120396 0.3048)
			(stroke
				(width 0.1)
				(type default)
			)
			(layer "B.Fab")
		)
		(fp_line
			(start -0.120396 0.3048)
			(end -0.120396 0.2794)
			(stroke
				(width 0.1)
				(type default)
			)
			(layer "B.Fab")
		)
		(fp_line
			(start 0.12065 0.3048)
			(end 0.67945 0.3048)
			(stroke
				(width 0.1)
				(type default)
			)
			(layer "B.Fab")
		)
		(fp_line
			(start 0.67945 0.3048)
			(end 0.67945 -0.305054)
			(stroke
				(width 0.1)
				(type default)
			)
			(layer "B.Fab")
		)
		(fp_line
			(start -0.120396 0.2794)
			(end 0.12065 0.2794)
			(stroke
				(width 0.1)
				(type default)
			)
			(layer "B.Fab")
		)
		(fp_line
			(start 0.12065 0.2794)
			(end 0.12065 0.3048)
			(stroke
				(width 0.1)
				(type default)
			)
			(layer "B.Fab")
		)
		(fp_line
			(start -0.12065 -0.2794)
			(end -0.12065 -0.3048)
			(stroke
				(width 0.1)
				(type default)
			)
			(layer "B.Fab")
		)
		(fp_line
			(start 0.12065 -0.2794)
			(end -0.12065 -0.2794)
			(stroke
				(width 0.1)
				(type default)
			)
			(layer "B.Fab")
		)
		(fp_line
			(start -0.67945 -0.3048)
			(end -0.67945 0.3048)
			(stroke
				(width 0.1)
				(type default)
			)
			(layer "B.Fab")
		)
		(fp_line
			(start -0.12065 -0.3048)
			(end -0.67945 -0.3048)
			(stroke
				(width 0.1)
				(type default)
			)
			(layer "B.Fab")
		)
		(fp_line
			(start 0.12065 -0.305054)
			(end 0.12065 -0.2794)
			(stroke
				(width 0.1)
				(type default)
			)
			(layer "B.Fab")
		)
		(fp_line
			(start 0.67945 -0.305054)
			(end 0.12065 -0.305054)
			(stroke
				(width 0.1)
				(type default)
			)
			(layer "B.Fab")
		)
		(pad "1" smd circle
			(at 0.40005 0 90)
			(size 0 0)
			(layers "B.Cu" "B.Mask" "B.Paste")
			(net "P3V3_AUX")
		)
		(pad "2" smd circle
			(at -0.40005 0 90)
			(size 0 0)
			(layers "B.Cu" "B.Mask" "B.Paste")
			(net "LED_POSTCODE_A0")
		)
	)
	(footprint ""
		(layer "B.Cu")
		(at 18.288 -83.693 90)
		(property "Reference" "R303"
			(at 0 0 90)
			(layer "B.SilkS")
			(hide yes)
			(effects
				(font
					(size 1.27 1.27)
				)
				(justify mirror)
			)
		)
		(property "Value" ""
			(at 0 0 90)
			(layer "B.Fab")
			(effects
				(font
					(size 1.27 1.27)
				)
				(justify mirror)
			)
		)
		(duplicate_pad_numbers_are_jumpers no)
		(fp_line
			(start 0.7874 -0.4064)
			(end -0.7874 -0.4064)
			(stroke
				(width 0.1524)
				(type default)
			)
			(layer "B.SilkS")
		)
		(fp_line
			(start -0.7874 -0.4064)
			(end -0.7874 0.4064)
			(stroke
				(width 0.1524)
				(type default)
			)
			(layer "B.SilkS")
		)
		(fp_line
			(start 0.7874 0.4064)
			(end 0.7874 -0.4064)
			(stroke
				(width 0.1524)
				(type default)
			)
			(layer "B.SilkS")
		)
		(fp_line
			(start -0.7874 0.4064)
			(end 0.7874 0.4064)
			(stroke
				(width 0.1524)
				(type default)
			)
			(layer "B.SilkS")
		)
		(fp_line
			(start 0.67945 -0.305054)
			(end 0.12065 -0.305054)
			(stroke
				(width 0.1)
				(type default)
			)
			(layer "B.Fab")
		)
		(fp_line
			(start 0.12065 -0.305054)
			(end 0.12065 -0.2794)
			(stroke
				(width 0.1)
				(type default)
			)
			(layer "B.Fab")
		)
		(fp_line
			(start -0.12065 -0.3048)
			(end -0.67945 -0.3048)
			(stroke
				(width 0.1)
				(type default)
			)
			(layer "B.Fab")
		)
		(fp_line
			(start -0.67945 -0.3048)
			(end -0.67945 0.3048)
			(stroke
				(width 0.1)
				(type default)
			)
			(layer "B.Fab")
		)
		(fp_line
			(start 0.12065 -0.2794)
			(end -0.12065 -0.2794)
			(stroke
				(width 0.1)
				(type default)
			)
			(layer "B.Fab")
		)
		(fp_line
			(start -0.12065 -0.2794)
			(end -0.12065 -0.3048)
			(stroke
				(width 0.1)
				(type default)
			)
			(layer "B.Fab")
		)
		(fp_line
			(start 0.12065 0.2794)
			(end 0.12065 0.3048)
			(stroke
				(width 0.1)
				(type default)
			)
			(layer "B.Fab")
		)
		(fp_line
			(start -0.120396 0.2794)
			(end 0.12065 0.2794)
			(stroke
				(width 0.1)
				(type default)
			)
			(layer "B.Fab")
		)
		(fp_line
			(start 0.67945 0.3048)
			(end 0.67945 -0.305054)
			(stroke
				(width 0.1)
				(type default)
			)
			(layer "B.Fab")
		)
		(fp_line
			(start 0.12065 0.3048)
			(end 0.67945 0.3048)
			(stroke
				(width 0.1)
				(type default)
			)
			(layer "B.Fab")
		)
		(fp_line
			(start -0.120396 0.3048)
			(end -0.120396 0.2794)
			(stroke
				(width 0.1)
				(type default)
			)
			(layer "B.Fab")
		)
		(fp_line
			(start -0.67945 0.3048)
			(end -0.120396 0.3048)
			(stroke
				(width 0.1)
				(type default)
			)
			(layer "B.Fab")
		)
		(pad "1" smd circle
			(at 0.40005 0 270)
			(size 0 0)
			(layers "B.Cu" "B.Mask" "B.Paste")
			(net "SMB_BMC_MM16_R3_SDA")
		)
		(pad "2" smd circle
			(at -0.40005 0 270)
			(size 0 0)
			(layers "B.Cu" "B.Mask" "B.Paste")
			(net "SMB_BMC_MM16_R5_SDA")
		)
	)
)
